FILE_TYPE = CONNECTIVITY;
{Allegro Design Entry HDL 16.6-p007 (v16-6-112F) 10/10/2012}
"PAGE_NUMBER" = 51;
0"NC";
1"M_E_DQS_DP<17:0>";
2"M_E_DQS_DN<17:0>";
3"M_E_DQ<63:0>";
4"M_E_MA<17:0>";
5"M_E_BA<1:0>";
6"M_E_BG<1:0>";
7"M_E_CS_N<7:0>";
8"M_E_ECC<7:0>";
9"M_E_ODT<3:0>";
10"M_E_CLK_DN<3:0>";
11"M_E_CLK_DP<3:0>";
12"M_E_CKE<3:0>";
13"PVDDQ_DEF\g";
14"GND\g";
15"PVTT_DEF\g";
16"GND\g";
17"GND\g";
18"PVPP_DEF\g";
19"PVPP_DEF\g";
20"P12V_NVDIMM_DEF\g";
21"GND\g";
22"TP_CH_E_DIMM_E0_RFU_2";
23"M_E_DQ<46>";
24"M_E_DQ<49>";
25"FM_ADR_COMPLETE_DEF_N";
26"M_E_MA<8>";
27"M_E_DQ<53>";
28"M_E_DQ<11>";
29"M_E_DQ<8>";
30"M_E_DQ<9>";
31"TP_CH_E_DIMM_E0_RFU_1";
32"TP_CH_E_DIMM_E0_RFU_0";
33"M_E_VREF";
34"SMB_DDR_DEF_VPP_SCL";
35"SMB_DDR_DEF_VPP_SDA";
36"FM_DIMM_EVENT_COD_N";
37"M_DEF_RST_N";
38"M_E_PAR";
39"M_E_CKE<0>";
40"M_E_CLK_DP<1>";
41"M_E_CKE<1>";
42"M_E_CLK_DP<0>";
43"M_E_CLK_DN<0>";
44"M_E_CLK_DN<1>";
45"M_E_ACT_N";
46"M_E_ALERT_N";
47"M_E_ECC<1>";
48"M_E_ECC<0>";
49"M_E_ECC<3>";
50"M_E_ECC<2>";
51"M_E_ECC<5>";
52"M_E_ECC<4>";
53"M_E_ECC<7>";
54"M_E_ODT<1>";
55"M_E_ODT<0>";
56"M_E_ECC<6>";
57"M_E_CS_N<0>";
58"M_E_CS_N<1>";
59"M_E_C<2>";
60"M_E_CS_N<2>";
61"M_E_CS_N<3>";
62"M_E_BG<0>";
63"M_E_BA<0>";
64"M_E_BG<1>";
65"M_E_MA<0>";
66"M_E_BA<1>";
67"M_E_DQ<4>";
68"M_E_DQ<5>";
69"M_E_DQ<2>";
70"M_E_DQ<3>";
71"M_E_DQ<1>";
72"M_E_DQ<0>";
73"M_E_DQ<14>";
74"M_E_DQ<7>";
75"M_E_DQ<6>";
76"M_E_DQ<10>";
77"M_E_DQ<13>";
78"M_E_DQ<15>";
79"M_E_DQ<17>";
80"M_E_DQ<12>";
81"M_E_DQ<16>";
82"M_E_DQ<27>";
83"M_E_DQ<19>";
84"M_E_DQ<18>";
85"M_E_DQ<21>";
86"M_E_DQ<23>";
87"M_E_DQ<22>";
88"M_E_DQ<25>";
89"M_E_DQ<24>";
90"M_E_DQ<20>";
91"M_E_DQ<26>";
92"M_E_DQ<37>";
93"M_E_DQ<34>";
94"M_E_DQ<31>";
95"M_E_DQ<30>";
96"M_E_DQ<33>";
97"M_E_DQ<32>";
98"M_E_DQ<35>";
99"M_E_DQ<29>";
100"M_E_DQ<28>";
101"M_E_DQ<39>";
102"M_E_DQ<36>";
103"M_E_DQ<38>";
104"M_E_DQ<41>";
105"M_E_DQ<40>";
106"M_E_DQ<43>";
107"M_E_DQ<42>";
108"M_E_DQ<45>";
109"M_E_DQ<44>";
110"M_E_DQ<47>";
111"M_E_MA<2>";
112"M_E_MA<6>";
113"M_E_MA<5>";
114"M_E_MA<4>";
115"M_E_MA<3>";
116"M_E_MA<1>";
117"M_E_MA<11>";
118"M_E_MA<10>";
119"M_E_MA<9>";
120"M_E_MA<7>";
121"M_E_MA<16>";
122"M_E_MA<15>";
123"M_E_MA<14>";
124"M_E_MA<13>";
125"M_E_MA<12>";
126"M_E_MA<17>";
127"M_E_DQ<48>";
128"M_E_DQ<51>";
129"M_E_DQ<50>";
130"M_E_DQ<52>";
131"M_E_DQ<55>";
132"M_E_DQ<56>";
133"M_E_DQ<54>";
134"M_E_DQ<57>";
135"M_E_DQ<62>";
136"M_E_DQ<63>";
137"M_E_DQ<60>";
138"M_E_DQ<59>";
139"M_E_DQ<58>";
140"M_E_DQ<61>";
141"M_E_DQS_DP<6>";
142"M_E_DQS_DN<6>";
143"M_E_DQS_DP<5>";
144"M_E_DQS_DN<5>";
145"M_E_DQS_DP<4>";
146"M_E_DQS_DN<4>";
147"M_E_DQS_DP<3>";
148"M_E_DQS_DN<3>";
149"M_E_DQS_DP<2>";
150"M_E_DQS_DN<2>";
151"M_E_DQS_DP<1>";
152"M_E_DQS_DN<1>";
153"M_E_DQS_DP<0>";
154"M_E_DQS_DN<0>";
155"M_E_DQS_DP<9>";
156"M_E_DQS_DN<9>";
157"M_E_DQS_DP<8>";
158"M_E_DQS_DN<8>";
159"M_E_DQS_DP<7>";
160"M_E_DQS_DN<7>";
161"M_E_DQS_DN<17>";
162"M_E_DQS_DP<16>";
163"M_E_DQS_DN<16>";
164"M_E_DQS_DP<15>";
165"M_E_DQS_DN<15>";
166"M_E_DQS_DP<14>";
167"M_E_DQS_DN<14>";
168"M_E_DQS_DP<13>";
169"M_E_DQS_DN<13>";
170"M_E_DQS_DP<12>";
171"M_E_DQS_DN<12>";
172"M_E_DQS_DP<11>";
173"M_E_DQS_DN<11>";
174"M_E_DQS_DP<10>";
175"M_E_DQS_DN<10>";
176"M_E_DQS_DP<17>";
%"TAP"
"6","(700,5050)","2","mstr_standard","I10";
;
CDS_LIB"mstr_standard"
BODY_TYPE"PLUMBING"
HDL_TAP"TRUE";
"B \NAC \NWC"1;
"S \NAC"
BN"16"162;
%"TAP"
"6","(-1600,2250)","2","mstr_standard","I100";
;
CDS_LIB"mstr_standard"
BODY_TYPE"PLUMBING"
HDL_TAP"TRUE";
"B \NAC \NWC"3;
"S \NAC"
BN"11"28;
%"TAP"
"6","(-1600,2200)","2","mstr_standard","I101";
;
CDS_LIB"mstr_standard"
BODY_TYPE"PLUMBING"
HDL_TAP"TRUE";
"B \NAC \NWC"3;
"S \NAC"
BN"8"29;
%"TAP"
"6","(-1600,2100)","2","mstr_standard","I102";
;
CDS_LIB"mstr_standard"
BODY_TYPE"PLUMBING"
HDL_TAP"TRUE";
"B \NAC \NWC"3;
"S \NAC"
BN"6"75;
%"TAP"
"6","(-1600,2150)","2","mstr_standard","I103";
;
CDS_LIB"mstr_standard"
BODY_TYPE"PLUMBING"
HDL_TAP"TRUE";
"B \NAC \NWC"3;
"S \NAC"
BN"9"30;
%"TAP"
"6","(-1600,2050)","2","mstr_standard","I104";
;
CDS_LIB"mstr_standard"
BODY_TYPE"PLUMBING"
HDL_TAP"TRUE";
"B \NAC \NWC"3;
"S \NAC"
BN"7"74;
%"TAP"
"6","(-1600,2000)","2","mstr_standard","I105";
;
CDS_LIB"mstr_standard"
BODY_TYPE"PLUMBING"
HDL_TAP"TRUE";
"B \NAC \NWC"3;
"S \NAC"
BN"4"67;
%"TAP"
"6","(-1600,1900)","2","mstr_standard","I106";
;
CDS_LIB"mstr_standard"
BODY_TYPE"PLUMBING"
HDL_TAP"TRUE";
"B \NAC \NWC"3;
"S \NAC"
BN"2"69;
%"TAP"
"6","(-1600,1950)","2","mstr_standard","I107";
;
CDS_LIB"mstr_standard"
BODY_TYPE"PLUMBING"
HDL_TAP"TRUE";
"B \NAC \NWC"3;
"S \NAC"
BN"5"68;
%"TAP"
"6","(-1600,1800)","2","mstr_standard","I108";
;
CDS_LIB"mstr_standard"
BODY_TYPE"PLUMBING"
HDL_TAP"TRUE";
"B \NAC \NWC"3;
"S \NAC"
BN"0"72;
%"TAP"
"6","(-1600,1850)","2","mstr_standard","I109";
;
CDS_LIB"mstr_standard"
BODY_TYPE"PLUMBING"
HDL_TAP"TRUE";
"B \NAC \NWC"3;
"S \NAC"
BN"3"70;
%"TAP"
"6","(700,4950)","2","mstr_standard","I11";
;
CDS_LIB"mstr_standard"
BODY_TYPE"PLUMBING"
HDL_TAP"TRUE";
"B \NAC \NWC"1;
"S \NAC"
BN"15"164;
%"TAP"
"6","(-1600,1750)","2","mstr_standard","I110";
;
CDS_LIB"mstr_standard"
BODY_TYPE"PLUMBING"
HDL_TAP"TRUE";
"B \NAC \NWC"3;
"S \NAC"
BN"1"71;
%"SCONN288_H44441004"
"1","(-2350,3250)","0","mstr_sconn","I111";
;
CDS_SEC"1"
LOCATION"J4A2"
MATERIAL"SCONN"
PART_NUMBER"H44441-004"
PACK_TYPE"PIP"
BOM_COST"MEM"
CDS_LIB"mstr_sconn"
SEC_TYPE"PIP"
SEC"1"
CDS_LOCATION"J4A2"
ROOM"DDR4_CH_E";
"DQ<63>"
$PN"280"135;
"DQ<62>"
$PN"135"136;
"DQ<61>"
$PN"273"137;
"DQ<5>"
$PN"148"67;
"DQ<4>"
$PN"3"68;
"DQ<3>"
$PN"157"69;
"DQ<2>"
$PN"12"70;
"DQ<47>"
$PN"258"23;
"DQ<48>"
$PN"119"24;
"DQ<49>"
$PN"264"127;
"DQ<50>"
$PN"126"128;
"DQ<51>"
$PN"271"129;
"DQ<52>"
$PN"117"27;
"DQ<53>"
$PN"262"130;
"DQ<54>"
$PN"124"131;
"DQ<58>"
$PN"137"138;
"DQ<57>"
$PN"275"132;
"SAVE_N_NC"
$PN"230"25;
"RFU<1>"
$PN"227"31;
"RFU<0>"
$PN"205"32;
"DQ<17>"
$PN"172"81;
"DQ<15>"
$PN"166"73;
"DQ<26>"
$PN"45"82;
"DQ<27>"
$PN"190"91;
"S0_N"
$PN"84"57;
"CKE<0>"
$PN"60"39;
"ODT<1>"
$PN"91"54;
"ODT<0>"
$PN"87"55;
"CB<7>"
$PN"199"56;
"A16_RAS_N"
$PN"82"121;
"A15_CAS_N"
$PN"86"122;
"A14_WE_N"
$PN"228"123;
"A11"
$PN"210"117;
"A10"
$PN"225"118;
"DQ<38>"
$PN"102"101;
"DQ<36>"
$PN"95"92;
"DQ<35>"
$PN"249"93;
"A2"
$PN"216"111;
"ALERT_N"
$PN"208"46;
"ACT_N"
$PN"62"45;
"DQ<0>"
$PN"5"71;
"DQ<1>"
$PN"150"72;
"SA<1>"
$PN"140"19;
"SA<2>"
$PN"238"16;
"VDDSPD"
$PN"284"19;
"SA<0>"
$PN"139"16;
"BA<0>"
$PN"81"63;
"BG<1>"
$PN"207"64;
"BG<0>"
$PN"63"62;
"CK1P"
$PN"218"40;
"VREFCA"
$PN"146"33;
"SDA"
$PN"285"35;
"SCL"
$PN"141"34;
"RFU<2>"
$PN"144"22;
"RESET_N"
$PN"58"37;
"PAR"
$PN"222"38;
"EVENT_N"
$PN"78"36;
"DQ<6>"
$PN"10"74;
"DQ<7>"
$PN"155"75;
"DQ<8>"
$PN"16"30;
"DQ<9>"
$PN"161"29;
"DQ<10>"
$PN"23"28;
"DQ<11>"
$PN"168"76;
"DQ<12>"
$PN"14"77;
"DQ<13>"
$PN"159"80;
"DQ<14>"
$PN"21"78;
"DQ<16>"
$PN"27"79;
"DQ<18>"
$PN"34"83;
"DQ<19>"
$PN"179"84;
"DQ<20>"
$PN"25"85;
"DQ<21>"
$PN"170"90;
"DQ<22>"
$PN"32"86;
"DQ<23>"
$PN"177"87;
"DQ<24>"
$PN"38"88;
"DQ<25>"
$PN"183"89;
"DQ<30>"
$PN"43"94;
"DQ<31>"
$PN"188"95;
"DQ<32>"
$PN"97"96;
"DQ<33>"
$PN"242"97;
"DQ<34>"
$PN"104"98;
"DQ<37>"
$PN"240"102;
"DQ<39>"
$PN"247"103;
"DQ<40>"
$PN"108"104;
"DQ<41>"
$PN"253"105;
"DQ<42>"
$PN"115"106;
"DQ<43>"
$PN"260"107;
"DQ<44>"
$PN"106"108;
"DQ<45>"
$PN"251"109;
"DQ<46>"
$PN"113"110;
"DQ<55>"
$PN"269"133;
"DQ<56>"
$PN"130"134;
"DQ<59>"
$PN"282"139;
"DQ<60>"
$PN"128"140;
"CKE<1>"
$PN"203"41;
"CK0N"
$PN"75"43;
"CB<0>"
$PN"49"47;
"CB<1>"
$PN"194"48;
"CB<2>"
$PN"56"49;
"CB<3>"
$PN"201"50;
"CB<4>"
$PN"47"51;
"CB<5>"
$PN"192"52;
"CB<6>"
$PN"54"53;
"A9"
$PN"66"119;
"A8"
$PN"68"26;
"A7"
$PN"211"120;
"A6"
$PN"69"112;
"A5"
$PN"213"113;
"A4"
$PN"214"114;
"A3"
$PN"71"115;
"A17"
$PN"234"126;
"A13"
$PN"232"124;
"A12"
$PN"65"125;
"A1"
$PN"72"116;
"A0"
$PN"79"65;
"C<2>"
$PN"235"59;
"DQ<28>"
$PN"36"99;
"DQ<29>"
$PN"181"100;
"S1_N"
$PN"89"58;
"S2_N_C<0>"
$PN"93"60;
"S3_N_C<1>"
$PN"237"61;
"CK0P"
$PN"74"42;
"CK1N"
$PN"219"44;
"BA<1>"
$PN"224"66;
%"TAP"
"6","(-3100,4900)","0","mstr_standard","I112";
;
CDS_LIB"mstr_standard"
BODY_TYPE"PLUMBING"
HDL_TAP"TRUE";
"B \NAC \NWC"4;
"S \NAC"
BN"17"126;
%"TAP"
"6","(-3100,4850)","0","mstr_standard","I113";
;
CDS_LIB"mstr_standard"
BODY_TYPE"PLUMBING"
HDL_TAP"TRUE";
"B \NAC \NWC"4;
"S \NAC"
BN"16"121;
%"TAP"
"6","(-3100,4800)","0","mstr_standard","I114";
;
CDS_LIB"mstr_standard"
BODY_TYPE"PLUMBING"
HDL_TAP"TRUE";
"B \NAC \NWC"4;
"S \NAC"
BN"15"122;
%"TAP"
"6","(-3100,4750)","0","mstr_standard","I115";
;
CDS_LIB"mstr_standard"
BODY_TYPE"PLUMBING"
HDL_TAP"TRUE";
"B \NAC \NWC"4;
"S \NAC"
BN"14"123;
%"TAP"
"6","(-3100,4700)","0","mstr_standard","I116";
;
CDS_LIB"mstr_standard"
BODY_TYPE"PLUMBING"
HDL_TAP"TRUE";
"B \NAC \NWC"4;
"S \NAC"
BN"13"124;
%"TAP"
"6","(-3100,4650)","0","mstr_standard","I117";
;
CDS_LIB"mstr_standard"
BODY_TYPE"PLUMBING"
HDL_TAP"TRUE";
"B \NAC \NWC"4;
"S \NAC"
BN"12"125;
%"TAP"
"6","(-3100,4600)","0","mstr_standard","I118";
;
CDS_LIB"mstr_standard"
BODY_TYPE"PLUMBING"
HDL_TAP"TRUE";
"B \NAC \NWC"4;
"S \NAC"
BN"11"117;
%"TAP"
"6","(-3100,4550)","0","mstr_standard","I119";
;
CDS_LIB"mstr_standard"
BODY_TYPE"PLUMBING"
HDL_TAP"TRUE";
"B \NAC \NWC"4;
"S \NAC"
BN"10"118;
%"TAP"
"6","(700,4850)","2","mstr_standard","I12";
;
CDS_LIB"mstr_standard"
BODY_TYPE"PLUMBING"
HDL_TAP"TRUE";
"B \NAC \NWC"1;
"S \NAC"
BN"14"166;
%"TAP"
"6","(-3100,4500)","0","mstr_standard","I120";
;
CDS_LIB"mstr_standard"
BODY_TYPE"PLUMBING"
HDL_TAP"TRUE";
"B \NAC \NWC"4;
"S \NAC"
BN"9"119;
%"TAP"
"6","(-3100,4450)","0","mstr_standard","I121";
;
CDS_LIB"mstr_standard"
BODY_TYPE"PLUMBING"
HDL_TAP"TRUE";
"B \NAC \NWC"4;
"S \NAC"
BN"8"26;
%"TAP"
"6","(-3100,4400)","0","mstr_standard","I122";
;
CDS_LIB"mstr_standard"
BODY_TYPE"PLUMBING"
HDL_TAP"TRUE";
"B \NAC \NWC"4;
"S \NAC"
BN"7"120;
%"TAP"
"6","(-3100,4350)","0","mstr_standard","I123";
;
CDS_LIB"mstr_standard"
BODY_TYPE"PLUMBING"
HDL_TAP"TRUE";
"B \NAC \NWC"4;
"S \NAC"
BN"6"112;
%"TAP"
"6","(-3100,4300)","0","mstr_standard","I124";
;
CDS_LIB"mstr_standard"
BODY_TYPE"PLUMBING"
HDL_TAP"TRUE";
"B \NAC \NWC"4;
"S \NAC"
BN"5"113;
%"TAP"
"6","(-3100,4250)","0","mstr_standard","I125";
;
CDS_LIB"mstr_standard"
BODY_TYPE"PLUMBING"
HDL_TAP"TRUE";
"B \NAC \NWC"4;
"S \NAC"
BN"4"114;
%"TAP"
"6","(-3100,4200)","0","mstr_standard","I126";
;
CDS_LIB"mstr_standard"
BODY_TYPE"PLUMBING"
HDL_TAP"TRUE";
"B \NAC \NWC"4;
"S \NAC"
BN"3"115;
%"TAP"
"6","(-3100,4150)","0","mstr_standard","I127";
;
CDS_LIB"mstr_standard"
BODY_TYPE"PLUMBING"
HDL_TAP"TRUE";
"B \NAC \NWC"4;
"S \NAC"
BN"2"111;
%"TAP"
"6","(-3100,4100)","0","mstr_standard","I128";
;
CDS_LIB"mstr_standard"
BODY_TYPE"PLUMBING"
HDL_TAP"TRUE";
"B \NAC \NWC"4;
"S \NAC"
BN"1"116;
%"TAP"
"6","(-3100,4050)","0","mstr_standard","I129";
;
CDS_LIB"mstr_standard"
BODY_TYPE"PLUMBING"
HDL_TAP"TRUE";
"B \NAC \NWC"4;
"S \NAC"
BN"0"65;
%"TAP"
"6","(700,4750)","2","mstr_standard","I13";
;
CDS_LIB"mstr_standard"
BODY_TYPE"PLUMBING"
HDL_TAP"TRUE";
"B \NAC \NWC"1;
"S \NAC"
BN"13"168;
%"TAP"
"6","(-3100,3950)","0","mstr_standard","I130";
;
CDS_LIB"mstr_standard"
BODY_TYPE"PLUMBING"
HDL_TAP"TRUE";
"B \NAC \NWC"5;
"S \NAC"
BN"1"66;
%"TAP"
"6","(-3100,3900)","0","mstr_standard","I133";
;
CDS_LIB"mstr_standard"
BODY_TYPE"PLUMBING"
HDL_TAP"TRUE";
"B \NAC \NWC"5;
"S \NAC"
BN"0"63;
%"TAP"
"6","(-3100,3850)","0","mstr_standard","I134";
;
CDS_LIB"mstr_standard"
BODY_TYPE"PLUMBING"
HDL_TAP"TRUE";
"B \NAC \NWC"6;
"S \NAC"
BN"1"64;
%"TAP"
"6","(-3100,3800)","0","mstr_standard","I135";
;
CDS_LIB"mstr_standard"
BODY_TYPE"PLUMBING"
HDL_TAP"TRUE";
"B \NAC \NWC"6;
"S \NAC"
BN"0"62;
%"TAP"
"6","(-3100,2800)","0","mstr_standard","I138";
;
CDS_LIB"mstr_standard"
BODY_TYPE"PLUMBING"
HDL_TAP"TRUE";
"B \NAC \NWC"8;
"S \NAC"
BN"7"53;
%"TAP"
"6","(-3100,2850)","0","mstr_standard","I139";
;
CDS_LIB"mstr_standard"
BODY_TYPE"PLUMBING"
HDL_TAP"TRUE";
"B \NAC \NWC"8;
"S \NAC"
BN"6"56;
%"TAP"
"6","(700,4550)","2","mstr_standard","I14";
;
CDS_LIB"mstr_standard"
BODY_TYPE"PLUMBING"
HDL_TAP"TRUE";
"B \NAC \NWC"1;
"S \NAC"
BN"11"172;
%"TAP"
"6","(-3100,2750)","0","mstr_standard","I140";
;
CDS_LIB"mstr_standard"
BODY_TYPE"PLUMBING"
HDL_TAP"TRUE";
"B \NAC \NWC"8;
"S \NAC"
BN"4"52;
%"TAP"
"6","(-3100,2700)","0","mstr_standard","I141";
;
CDS_LIB"mstr_standard"
BODY_TYPE"PLUMBING"
HDL_TAP"TRUE";
"B \NAC \NWC"8;
"S \NAC"
BN"5"51;
%"TAP"
"6","(-3100,2650)","0","mstr_standard","I142";
;
CDS_LIB"mstr_standard"
BODY_TYPE"PLUMBING"
HDL_TAP"TRUE";
"B \NAC \NWC"8;
"S \NAC"
BN"2"50;
%"TAP"
"6","(-3100,2600)","0","mstr_standard","I143";
;
CDS_LIB"mstr_standard"
BODY_TYPE"PLUMBING"
HDL_TAP"TRUE";
"B \NAC \NWC"8;
"S \NAC"
BN"3"49;
%"TAP"
"6","(-3100,2550)","0","mstr_standard","I144";
;
CDS_LIB"mstr_standard"
BODY_TYPE"PLUMBING"
HDL_TAP"TRUE";
"B \NAC \NWC"8;
"S \NAC"
BN"0"48;
%"TAP"
"6","(-3100,2500)","0","mstr_standard","I145";
;
CDS_LIB"mstr_standard"
BODY_TYPE"PLUMBING"
HDL_TAP"TRUE";
"B \NAC \NWC"8;
"S \NAC"
BN"1"47;
%"TAP"
"6","(700,4650)","2","mstr_standard","I15";
;
CDS_LIB"mstr_standard"
BODY_TYPE"PLUMBING"
HDL_TAP"TRUE";
"B \NAC \NWC"1;
"S \NAC"
BN"12"170;
%"TAP"
"6","(-3500,3600)","0","mstr_standard","I152";
;
CDS_LIB"mstr_standard"
BODY_TYPE"PLUMBING"
HDL_TAP"TRUE";
"B \NAC \NWC"11;
"S \NAC"
BN"0"42;
%"TAP"
"6","(-3650,3550)","0","mstr_standard","I153";
;
CDS_LIB"mstr_standard"
BODY_TYPE"PLUMBING"
HDL_TAP"TRUE";
"B \NAC \NWC"10;
"S \NAC"
BN"0"43;
%"TAP"
"6","(-3100,3400)","0","mstr_standard","I156";
;
CDS_LIB"mstr_standard"
BODY_TYPE"PLUMBING"
HDL_TAP"TRUE";
"B \NAC \NWC"7;
"S \NAC"
BN"3"61;
%"TAP"
"6","(-3100,3350)","0","mstr_standard","I157";
;
CDS_LIB"mstr_standard"
BODY_TYPE"PLUMBING"
HDL_TAP"TRUE";
"B \NAC \NWC"7;
"S \NAC"
BN"2"60;
%"TAP"
"6","(-3100,3300)","0","mstr_standard","I158";
;
CDS_LIB"mstr_standard"
BODY_TYPE"PLUMBING"
HDL_TAP"TRUE";
"B \NAC \NWC"7;
"S \NAC"
BN"1"58;
%"TAP"
"6","(-3100,3250)","0","mstr_standard","I159";
;
CDS_LIB"mstr_standard"
BODY_TYPE"PLUMBING"
HDL_TAP"TRUE";
"B \NAC \NWC"7;
"S \NAC"
BN"0"57;
%"PVDDQ_DEF"
"1","(-1225,2600)","0","mstr_symbols","I16";
;
VOLTAGE"1.2V"
BOM_COST"MEM"
CDS_LIB"mstr_symbols"
BODY_TYPE"PLUMBING"
ROOM"DDR4_CH_B"
HDL_POWER"PVDDQ_DEF";
"G\NAC"13;
%"TAP"
"6","(-3150,3150)","0","mstr_standard","I160";
;
CDS_LIB"mstr_standard"
BODY_TYPE"PLUMBING"
HDL_TAP"TRUE";
"B \NAC \NWC"12;
"S \NAC"
BN"1"41;
%"TAP"
"6","(-3150,3100)","0","mstr_standard","I163";
;
CDS_LIB"mstr_standard"
BODY_TYPE"PLUMBING"
HDL_TAP"TRUE";
"B \NAC \NWC"12;
"S \NAC"
BN"0"39;
%"TAP"
"6","(-3100,3000)","0","mstr_standard","I164";
;
CDS_LIB"mstr_standard"
BODY_TYPE"PLUMBING"
HDL_TAP"TRUE";
"B \NAC \NWC"9;
"S \NAC"
BN"1"54;
%"TAP"
"6","(-3100,2950)","0","mstr_standard","I166";
;
CDS_LIB"mstr_standard"
BODY_TYPE"PLUMBING"
HDL_TAP"TRUE";
"B \NAC \NWC"9;
"S \NAC"
BN"0"55;
%"SCONN288_H44441004"
"4","(-150,2050)","0","mstr_sconn","I167";
;
CDS_SEC"4"
LOCATION"J4A2"
PART_NUMBER"H44441-004"
MATERIAL"SCONN"
PACK_TYPE"PIP"
BOM_COST"MEM"
CDS_LIB"mstr_sconn"
SEC_TYPE"PIP"
SEC"4"
CDS_LOCATION"J4A2"
ROOM"DDR4_CH_E";
"VPP<4>"
$PN"142"18;
"VTT<1>"
$PN"77"15;
"VPP<0>"
$PN"287"18;
"VPP<1>"
$PN"286"18;
"VPP<2>"
$PN"288"18;
"VPP<3>"
$PN"143"18;
"VDD<1>"
$PN"233"13;
"VDD<2>"
$PN"231"13;
"VDD<3>"
$PN"229"13;
"VDD<4>"
$PN"226"13;
"VDD<5>"
$PN"223"13;
"VDD<7>"
$PN"217"13;
"VDD<8>"
$PN"215"13;
"VDD<9>"
$PN"212"13;
"VDD<11>"
$PN"206"13;
"VDD<12>"
$PN"204"13;
"VDD<14>"
$PN"90"13;
"VDD<15>"
$PN"88"13;
"VDD<17>"
$PN"83"13;
"VDD<18>"
$PN"80"13;
"VDD<20>"
$PN"73"13;
"VDD<21>"
$PN"70"13;
"VDD<22>"
$PN"67"13;
"VDD<24>"
$PN"61"13;
"12V<0>"
$PN"145"20;
"12V<1>"
$PN"1"20;
"VTT<0>"
$PN"221"15;
"VDD<25>"
$PN"59"13;
"VDD<23>"
$PN"64"13;
"VDD<19>"
$PN"76"13;
"VDD<16>"
$PN"85"13;
"VDD<13>"
$PN"92"13;
"VDD<10>"
$PN"209"13;
"VDD<6>"
$PN"220"13;
"VDD<0>"
$PN"236"13;
%"GND"
"1","(2500,1200)","2","mstr_symbols","I168";
;
VOLTAGE"0"
SIZE"1B"
CDS_LIB"mstr_symbols"
BOM_COST"MEM"
BODY_TYPE"PLUMBING"
ROOM"DDR4_CH_B"
HDL_POWER"GND";
"A\NAC"14;
%"PVTT_DEF"
"1","(-1000,2750)","0","mstr_symbols","I17";
;
VOLTAGE"0.6V"
BOM_COST"MEM"
CDS_LIB"mstr_symbols"
BODY_TYPE"PLUMBING"
ROOM"DDR4_CH_B"
HDL_POWER"PVTT_DEF";
"G\NAC"15;
%"GND"
"1","(-5200,1800)","2","mstr_symbols","I174";
;
VOLTAGE"0"
SIZE"1B"
CDS_LIB"mstr_symbols"
BOM_COST"MEM"
BODY_TYPE"PLUMBING"
ROOM"DDR4_CH_B"
HDL_POWER"GND";
"A\NAC"16;
%"CAP_A"
"1","(-4650,1550)","2","dev_discrete","I175";
;
CDS_SEC"1"
LOCATION"C6L6"
PART_NUMBER"A36096-045"
VALUE"0.01UF"
TOLERANCE"10%"
VOLTAGE"25V"
MATERIAL"X7R"
PACK_TYPE"0402V"
CDS_LOCATION"C6L6"
BOM_COST"MEM"
CDS_LIB"dev_discrete"
ROOM"DDR4_CH_E"
SEC"1"
SEC_TYPE"0402V";
"B"
$PN"2"17;
"A"
$PN"1"33;
%"GND"
"1","(-4650,1300)","2","mstr_symbols","I176";
;
VOLTAGE"0"
BOM_COST"MEM"
CDS_LIB"mstr_symbols"
SIZE"1B"
BODY_TYPE"PLUMBING"
ROOM"DDR4_CH_B"
HDL_POWER"GND";
"A\NAC"17;
%"PVPP_DEF"
"1","(-850,3050)","0","mstr_symbols","I177";
;
VOLTAGE"2.5V"
BOM_COST"MEM"
CDS_LIB"mstr_symbols"
BODY_TYPE"PLUMBING"
ROOM"DDR4_CH_B"
HDL_POWER"PVPP_DEF";
"G\NAC"18;
%"PVPP_DEF"
"1","(-5200,2250)","0","mstr_symbols","I178";
;
VOLTAGE"2.5V"
BOM_COST"MEM"
CDS_LIB"mstr_symbols"
BODY_TYPE"PLUMBING"
ROOM"DDR4_CH_B"
HDL_POWER"PVPP_DEF";
"G\NAC"19;
%"TAP"
"6","(-3500,3700)","0","mstr_standard","I183";
;
CDS_LIB"mstr_standard"
BODY_TYPE"PLUMBING"
HDL_TAP"TRUE";
"B \NAC \NWC"11;
"S \NAC"
BN"1"40;
%"TAP"
"6","(-3650,3650)","0","mstr_standard","I184";
;
CDS_LIB"mstr_standard"
BODY_TYPE"PLUMBING"
HDL_TAP"TRUE";
"B \NAC \NWC"10;
"S \NAC"
BN"1"44;
%"P12V_NVDIMM_DEF"
"1","(550,3125)","0","mstr_symbols","I185";
;
VOLTAGE"12.0"
CDS_LIB"mstr_symbols"
BODY_TYPE"PLUMBING"
HDL_POWER"P12V_NVDIMM_DEF";
"G\NAC"20;
%"TAP"
"6","(900,4500)","2","mstr_standard","I19";
;
CDS_LIB"mstr_standard"
BODY_TYPE"PLUMBING"
HDL_TAP"TRUE";
"B \NAC \NWC"2;
"S \NAC"
BN"11"173;
%"TAP"
"6","(900,4400)","2","mstr_standard","I20";
;
CDS_LIB"mstr_standard"
BODY_TYPE"PLUMBING"
HDL_TAP"TRUE";
"B \NAC \NWC"2;
"S \NAC"
BN"10"175;
%"TAP"
"6","(900,4300)","2","mstr_standard","I21";
;
CDS_LIB"mstr_standard"
BODY_TYPE"PLUMBING"
HDL_TAP"TRUE";
"B \NAC \NWC"2;
"S \NAC"
BN"9"156;
%"TAP"
"6","(900,4200)","2","mstr_standard","I22";
;
CDS_LIB"mstr_standard"
BODY_TYPE"PLUMBING"
HDL_TAP"TRUE";
"B \NAC \NWC"2;
"S \NAC"
BN"8"158;
%"TAP"
"6","(900,4100)","2","mstr_standard","I23";
;
CDS_LIB"mstr_standard"
BODY_TYPE"PLUMBING"
HDL_TAP"TRUE";
"B \NAC \NWC"2;
"S \NAC"
BN"7"160;
%"TAP"
"6","(700,4350)","2","mstr_standard","I24";
;
CDS_LIB"mstr_standard"
BODY_TYPE"PLUMBING"
HDL_TAP"TRUE";
"B \NAC \NWC"1;
"S \NAC"
BN"9"155;
%"TAP"
"6","(700,4450)","2","mstr_standard","I25";
;
CDS_LIB"mstr_standard"
BODY_TYPE"PLUMBING"
HDL_TAP"TRUE";
"B \NAC \NWC"1;
"S \NAC"
BN"10"174;
%"TAP"
"6","(700,4250)","2","mstr_standard","I26";
;
CDS_LIB"mstr_standard"
BODY_TYPE"PLUMBING"
HDL_TAP"TRUE";
"B \NAC \NWC"1;
"S \NAC"
BN"8"157;
%"TAP"
"6","(700,4050)","2","mstr_standard","I27";
;
CDS_LIB"mstr_standard"
BODY_TYPE"PLUMBING"
HDL_TAP"TRUE";
"B \NAC \NWC"1;
"S \NAC"
BN"6"141;
%"TAP"
"6","(700,4150)","2","mstr_standard","I28";
;
CDS_LIB"mstr_standard"
BODY_TYPE"PLUMBING"
HDL_TAP"TRUE";
"B \NAC \NWC"1;
"S \NAC"
BN"7"159;
%"TAP"
"6","(900,4000)","2","mstr_standard","I29";
;
CDS_LIB"mstr_standard"
BODY_TYPE"PLUMBING"
HDL_TAP"TRUE";
"B \NAC \NWC"2;
"S \NAC"
BN"6"142;
%"TAP"
"6","(900,5100)","2","mstr_standard","I3";
;
CDS_LIB"mstr_standard"
BODY_TYPE"PLUMBING"
HDL_TAP"TRUE";
"B \NAC \NWC"2;
"S \NAC"
BN"17"161;
%"TAP"
"6","(900,3900)","2","mstr_standard","I30";
;
CDS_LIB"mstr_standard"
BODY_TYPE"PLUMBING"
HDL_TAP"TRUE";
"B \NAC \NWC"2;
"S \NAC"
BN"5"144;
%"TAP"
"6","(900,3800)","2","mstr_standard","I31";
;
CDS_LIB"mstr_standard"
BODY_TYPE"PLUMBING"
HDL_TAP"TRUE";
"B \NAC \NWC"2;
"S \NAC"
BN"4"146;
%"TAP"
"6","(900,3700)","2","mstr_standard","I32";
;
CDS_LIB"mstr_standard"
BODY_TYPE"PLUMBING"
HDL_TAP"TRUE";
"B \NAC \NWC"2;
"S \NAC"
BN"3"148;
%"TAP"
"6","(900,3600)","2","mstr_standard","I33";
;
CDS_LIB"mstr_standard"
BODY_TYPE"PLUMBING"
HDL_TAP"TRUE";
"B \NAC \NWC"2;
"S \NAC"
BN"2"150;
%"TAP"
"6","(700,3850)","2","mstr_standard","I34";
;
CDS_LIB"mstr_standard"
BODY_TYPE"PLUMBING"
HDL_TAP"TRUE";
"B \NAC \NWC"1;
"S \NAC"
BN"4"145;
%"TAP"
"6","(700,3950)","2","mstr_standard","I35";
;
CDS_LIB"mstr_standard"
BODY_TYPE"PLUMBING"
HDL_TAP"TRUE";
"B \NAC \NWC"1;
"S \NAC"
BN"5"143;
%"TAP"
"6","(700,3750)","2","mstr_standard","I36";
;
CDS_LIB"mstr_standard"
BODY_TYPE"PLUMBING"
HDL_TAP"TRUE";
"B \NAC \NWC"1;
"S \NAC"
BN"3"147;
%"TAP"
"6","(700,3650)","2","mstr_standard","I37";
;
CDS_LIB"mstr_standard"
BODY_TYPE"PLUMBING"
HDL_TAP"TRUE";
"B \NAC \NWC"1;
"S \NAC"
BN"2"149;
%"TAP"
"6","(700,3550)","2","mstr_standard","I38";
;
CDS_LIB"mstr_standard"
BODY_TYPE"PLUMBING"
HDL_TAP"TRUE";
"B \NAC \NWC"1;
"S \NAC"
BN"1"151;
%"TAP"
"6","(900,3400)","2","mstr_standard","I39";
;
CDS_LIB"mstr_standard"
BODY_TYPE"PLUMBING"
HDL_TAP"TRUE";
"B \NAC \NWC"2;
"S \NAC"
BN"0"154;
%"TAP"
"6","(700,5150)","2","mstr_standard","I4";
;
CDS_LIB"mstr_standard"
BODY_TYPE"PLUMBING"
HDL_TAP"TRUE";
"B \NAC \NWC"1;
"S \NAC"
BN"17"176;
%"TAP"
"6","(900,3500)","2","mstr_standard","I40";
;
CDS_LIB"mstr_standard"
BODY_TYPE"PLUMBING"
HDL_TAP"TRUE";
"B \NAC \NWC"2;
"S \NAC"
BN"1"152;
%"TAP"
"6","(700,3450)","2","mstr_standard","I41";
;
CDS_LIB"mstr_standard"
BODY_TYPE"PLUMBING"
HDL_TAP"TRUE";
"B \NAC \NWC"1;
"S \NAC"
BN"0"153;
%"SCONN288_H44441004"
"3","(1800,2500)","0","mstr_sconn","I43";
;
CDS_SEC"3"
PART_NUMBER"H44441-004"
MATERIAL"SCONN"
LOCATION"J4A2"
PACK_TYPE"PIP"
BOM_COST"MEM"
CDS_LIB"mstr_sconn"
SEC_TYPE"PIP"
SEC"3"
CDS_LOCATION"J4A2"
ROOM"DDR4_CH_E";
"VSS<93>"
$PN"2"21;
"VSS<92>"
$PN"4"21;
"VSS<91>"
$PN"6"21;
"VSS<90>"
$PN"9"21;
"VSS<89>"
$PN"11"21;
"VSS<88>"
$PN"13"21;
"VSS<0>"
$PN"283"14;
"VSS<1>"
$PN"281"14;
"VSS<2>"
$PN"279"14;
"VSS<3>"
$PN"276"14;
"VSS<4>"
$PN"274"14;
"VSS<5>"
$PN"272"14;
"VSS<6>"
$PN"270"14;
"VSS<7>"
$PN"268"14;
"VSS<8>"
$PN"265"14;
"VSS<9>"
$PN"263"14;
"VSS<10>"
$PN"261"14;
"VSS<11>"
$PN"259"14;
"VSS<12>"
$PN"257"14;
"VSS<13>"
$PN"254"14;
"VSS<14>"
$PN"252"14;
"VSS<15>"
$PN"250"14;
"VSS<16>"
$PN"248"14;
"VSS<17>"
$PN"246"14;
"VSS<18>"
$PN"243"14;
"VSS<19>"
$PN"241"14;
"VSS<20>"
$PN"239"14;
"VSS<21>"
$PN"202"14;
"VSS<22>"
$PN"200"14;
"VSS<23>"
$PN"198"14;
"VSS<24>"
$PN"195"14;
"VSS<25>"
$PN"193"14;
"VSS<26>"
$PN"191"14;
"VSS<27>"
$PN"189"14;
"VSS<28>"
$PN"187"14;
"VSS<29>"
$PN"184"14;
"VSS<30>"
$PN"182"14;
"VSS<31>"
$PN"180"14;
"VSS<32>"
$PN"178"14;
"VSS<33>"
$PN"176"14;
"VSS<34>"
$PN"173"14;
"VSS<35>"
$PN"171"14;
"VSS<36>"
$PN"169"14;
"VSS<37>"
$PN"167"14;
"VSS<38>"
$PN"165"14;
"VSS<39>"
$PN"162"14;
"VSS<40>"
$PN"160"14;
"VSS<41>"
$PN"158"14;
"VSS<42>"
$PN"156"14;
"VSS<43>"
$PN"154"14;
"VSS<44>"
$PN"151"14;
"VSS<47>"
$PN"138"21;
"VSS<48>"
$PN"136"21;
"VSS<49>"
$PN"134"21;
"VSS<50>"
$PN"131"21;
"VSS<51>"
$PN"129"21;
"VSS<52>"
$PN"127"21;
"VSS<53>"
$PN"125"21;
"VSS<54>"
$PN"123"21;
"VSS<55>"
$PN"120"21;
"VSS<56>"
$PN"118"21;
"VSS<57>"
$PN"116"21;
"VSS<58>"
$PN"114"21;
"VSS<59>"
$PN"112"21;
"VSS<60>"
$PN"109"21;
"VSS<61>"
$PN"107"21;
"VSS<62>"
$PN"105"21;
"VSS<63>"
$PN"103"21;
"VSS<64>"
$PN"101"21;
"VSS<65>"
$PN"98"21;
"VSS<66>"
$PN"96"21;
"VSS<67>"
$PN"94"21;
"VSS<68>"
$PN"57"21;
"VSS<69>"
$PN"55"21;
"VSS<70>"
$PN"53"21;
"VSS<71>"
$PN"50"21;
"VSS<72>"
$PN"48"21;
"VSS<73>"
$PN"46"21;
"VSS<74>"
$PN"44"21;
"VSS<75>"
$PN"42"21;
"VSS<76>"
$PN"39"21;
"VSS<77>"
$PN"37"21;
"VSS<78>"
$PN"35"21;
"VSS<79>"
$PN"33"21;
"VSS<80>"
$PN"31"21;
"VSS<81>"
$PN"28"21;
"VSS<82>"
$PN"26"21;
"VSS<83>"
$PN"24"21;
"VSS<84>"
$PN"22"21;
"VSS<85>"
$PN"20"21;
"VSS<86>"
$PN"17"21;
"VSS<87>"
$PN"15"21;
"VSS<45>"
$PN"149"14;
"VSS<46>"
$PN"147"14;
%"GND"
"1","(1100,1200)","2","mstr_symbols","I44";
;
VOLTAGE"0"
SIZE"1B"
CDS_LIB"mstr_symbols"
BOM_COST"MEM"
BODY_TYPE"PLUMBING"
ROOM"DDR4_CH_B"
HDL_POWER"GND";
"A\NAC"21;
%"TAP"
"6","(-1600,4900)","2","mstr_standard","I46";
;
CDS_LIB"mstr_standard"
BODY_TYPE"PLUMBING"
HDL_TAP"TRUE";
"B \NAC \NWC"3;
"S \NAC"
BN"62"135;
%"TAP"
"6","(-1600,4850)","2","mstr_standard","I47";
;
CDS_LIB"mstr_standard"
BODY_TYPE"PLUMBING"
HDL_TAP"TRUE";
"B \NAC \NWC"3;
"S \NAC"
BN"63"136;
%"TAP"
"6","(-1600,4750)","2","mstr_standard","I48";
;
CDS_LIB"mstr_standard"
BODY_TYPE"PLUMBING"
HDL_TAP"TRUE";
"B \NAC \NWC"3;
"S \NAC"
BN"61"140;
%"TAP"
"6","(-1600,4800)","2","mstr_standard","I49";
;
CDS_LIB"mstr_standard"
BODY_TYPE"PLUMBING"
HDL_TAP"TRUE";
"B \NAC \NWC"3;
"S \NAC"
BN"60"137;
%"TAP"
"6","(900,5000)","2","mstr_standard","I5";
;
CDS_LIB"mstr_standard"
BODY_TYPE"PLUMBING"
HDL_TAP"TRUE";
"B \NAC \NWC"2;
"S \NAC"
BN"16"163;
%"TAP"
"6","(-1600,4700)","2","mstr_standard","I50";
;
CDS_LIB"mstr_standard"
BODY_TYPE"PLUMBING"
HDL_TAP"TRUE";
"B \NAC \NWC"3;
"S \NAC"
BN"58"139;
%"TAP"
"6","(-1600,4600)","2","mstr_standard","I51";
;
CDS_LIB"mstr_standard"
BODY_TYPE"PLUMBING"
HDL_TAP"TRUE";
"B \NAC \NWC"3;
"S \NAC"
BN"56"132;
%"TAP"
"6","(-1600,4650)","2","mstr_standard","I52";
;
CDS_LIB"mstr_standard"
BODY_TYPE"PLUMBING"
HDL_TAP"TRUE";
"B \NAC \NWC"3;
"S \NAC"
BN"59"138;
%"TAP"
"6","(-1600,4550)","2","mstr_standard","I53";
;
CDS_LIB"mstr_standard"
BODY_TYPE"PLUMBING"
HDL_TAP"TRUE";
"B \NAC \NWC"3;
"S \NAC"
BN"57"134;
%"TAP"
"6","(-1600,4500)","2","mstr_standard","I54";
;
CDS_LIB"mstr_standard"
BODY_TYPE"PLUMBING"
HDL_TAP"TRUE";
"B \NAC \NWC"3;
"S \NAC"
BN"54"133;
%"TAP"
"6","(-1600,4400)","2","mstr_standard","I55";
;
CDS_LIB"mstr_standard"
BODY_TYPE"PLUMBING"
HDL_TAP"TRUE";
"B \NAC \NWC"3;
"S \NAC"
BN"52"130;
%"TAP"
"6","(-1600,4450)","2","mstr_standard","I56";
;
CDS_LIB"mstr_standard"
BODY_TYPE"PLUMBING"
HDL_TAP"TRUE";
"B \NAC \NWC"3;
"S \NAC"
BN"55"131;
%"TAP"
"6","(-1600,4350)","2","mstr_standard","I57";
;
CDS_LIB"mstr_standard"
BODY_TYPE"PLUMBING"
HDL_TAP"TRUE";
"B \NAC \NWC"3;
"S \NAC"
BN"53"27;
%"TAP"
"6","(-1600,4300)","2","mstr_standard","I58";
;
CDS_LIB"mstr_standard"
BODY_TYPE"PLUMBING"
HDL_TAP"TRUE";
"B \NAC \NWC"3;
"S \NAC"
BN"50"129;
%"TAP"
"6","(-1600,4250)","2","mstr_standard","I59";
;
CDS_LIB"mstr_standard"
BODY_TYPE"PLUMBING"
HDL_TAP"TRUE";
"B \NAC \NWC"3;
"S \NAC"
BN"51"128;
%"TAP"
"6","(900,4900)","2","mstr_standard","I6";
;
CDS_LIB"mstr_standard"
BODY_TYPE"PLUMBING"
HDL_TAP"TRUE";
"B \NAC \NWC"2;
"S \NAC"
BN"15"165;
%"TAP"
"6","(-1600,4200)","2","mstr_standard","I60";
;
CDS_LIB"mstr_standard"
BODY_TYPE"PLUMBING"
HDL_TAP"TRUE";
"B \NAC \NWC"3;
"S \NAC"
BN"48"127;
%"TAP"
"6","(-1600,4100)","2","mstr_standard","I61";
;
CDS_LIB"mstr_standard"
BODY_TYPE"PLUMBING"
HDL_TAP"TRUE";
"B \NAC \NWC"3;
"S \NAC"
BN"46"23;
%"TAP"
"6","(-1600,4150)","2","mstr_standard","I62";
;
CDS_LIB"mstr_standard"
BODY_TYPE"PLUMBING"
HDL_TAP"TRUE";
"B \NAC \NWC"3;
"S \NAC"
BN"49"24;
%"TAP"
"6","(-1600,4050)","2","mstr_standard","I63";
;
CDS_LIB"mstr_standard"
BODY_TYPE"PLUMBING"
HDL_TAP"TRUE";
"B \NAC \NWC"3;
"S \NAC"
BN"47"110;
%"TAP"
"6","(-1600,4000)","2","mstr_standard","I64";
;
CDS_LIB"mstr_standard"
BODY_TYPE"PLUMBING"
HDL_TAP"TRUE";
"B \NAC \NWC"3;
"S \NAC"
BN"44"109;
%"TAP"
"6","(-1600,3950)","2","mstr_standard","I65";
;
CDS_LIB"mstr_standard"
BODY_TYPE"PLUMBING"
HDL_TAP"TRUE";
"B \NAC \NWC"3;
"S \NAC"
BN"45"108;
%"SCONN288_H44441004"
"2","(0,4300)","0","mstr_sconn","I66";
;
CDS_SEC"2"
LOCATION"J4A2"
PART_NUMBER"H44441-004"
MATERIAL"SCONN"
PACK_TYPE"PIP"
BOM_COST"MEM"
CDS_LIB"mstr_sconn"
SEC_TYPE"PIP"
SEC"2"
CDS_LOCATION"J4A2"
ROOM"DDR4_CH_E";
"DQS17P"
$PN"51"176;
"DQS9P"
$PN"7"155;
"DQS9N"
$PN"8"156;
"DQS8P"
$PN"197"157;
"DQS8N"
$PN"196"158;
"DQS7P"
$PN"278"159;
"DQS7N"
$PN"277"160;
"DQS6P"
$PN"267"141;
"DQS6N"
$PN"266"142;
"DQS5P"
$PN"256"143;
"DQS5N"
$PN"255"144;
"DQS4P"
$PN"245"145;
"DQS4N"
$PN"244"146;
"DQS3P"
$PN"186"147;
"DQS3N"
$PN"185"148;
"DQS2P"
$PN"175"149;
"DQS2N"
$PN"174"150;
"DQS1P"
$PN"164"151;
"DQS1N"
$PN"163"152;
"DQS17N"
$PN"52"161;
"DQS16P"
$PN"132"162;
"DQS16N"
$PN"133"163;
"DQS15P"
$PN"121"164;
"DQS15N"
$PN"122"165;
"DQS14P"
$PN"110"166;
"DQS14N"
$PN"111"167;
"DQS13P"
$PN"99"168;
"DQS13N"
$PN"100"169;
"DQS12P"
$PN"40"170;
"DQS12N"
$PN"41"171;
"DQS11P"
$PN"29"172;
"DQS11N"
$PN"30"173;
"DQS10P"
$PN"18"174;
"DQS10N"
$PN"19"175;
"DQS0P"
$PN"153"153;
"DQS0N"
$PN"152"154;
%"TAP"
"6","(-1600,3900)","2","mstr_standard","I67";
;
CDS_LIB"mstr_standard"
BODY_TYPE"PLUMBING"
HDL_TAP"TRUE";
"B \NAC \NWC"3;
"S \NAC"
BN"42"107;
%"TAP"
"6","(-1600,3850)","2","mstr_standard","I68";
;
CDS_LIB"mstr_standard"
BODY_TYPE"PLUMBING"
HDL_TAP"TRUE";
"B \NAC \NWC"3;
"S \NAC"
BN"43"106;
%"TAP"
"6","(-1600,3750)","2","mstr_standard","I69";
;
CDS_LIB"mstr_standard"
BODY_TYPE"PLUMBING"
HDL_TAP"TRUE";
"B \NAC \NWC"3;
"S \NAC"
BN"41"104;
%"TAP"
"6","(900,4700)","2","mstr_standard","I7";
;
CDS_LIB"mstr_standard"
BODY_TYPE"PLUMBING"
HDL_TAP"TRUE";
"B \NAC \NWC"2;
"S \NAC"
BN"13"169;
%"TAP"
"6","(-1600,3700)","2","mstr_standard","I70";
;
CDS_LIB"mstr_standard"
BODY_TYPE"PLUMBING"
HDL_TAP"TRUE";
"B \NAC \NWC"3;
"S \NAC"
BN"38"103;
%"TAP"
"6","(-1600,3800)","2","mstr_standard","I71";
;
CDS_LIB"mstr_standard"
BODY_TYPE"PLUMBING"
HDL_TAP"TRUE";
"B \NAC \NWC"3;
"S \NAC"
BN"40"105;
%"TAP"
"6","(-1600,3650)","2","mstr_standard","I72";
;
CDS_LIB"mstr_standard"
BODY_TYPE"PLUMBING"
HDL_TAP"TRUE";
"B \NAC \NWC"3;
"S \NAC"
BN"39"101;
%"TAP"
"6","(-1600,3600)","2","mstr_standard","I73";
;
CDS_LIB"mstr_standard"
BODY_TYPE"PLUMBING"
HDL_TAP"TRUE";
"B \NAC \NWC"3;
"S \NAC"
BN"36"102;
%"TAP"
"6","(-1600,3550)","2","mstr_standard","I74";
;
CDS_LIB"mstr_standard"
BODY_TYPE"PLUMBING"
HDL_TAP"TRUE";
"B \NAC \NWC"3;
"S \NAC"
BN"37"92;
%"TAP"
"6","(-1600,3450)","2","mstr_standard","I75";
;
CDS_LIB"mstr_standard"
BODY_TYPE"PLUMBING"
HDL_TAP"TRUE";
"B \NAC \NWC"3;
"S \NAC"
BN"35"98;
%"TAP"
"6","(-1600,3500)","2","mstr_standard","I76";
;
CDS_LIB"mstr_standard"
BODY_TYPE"PLUMBING"
HDL_TAP"TRUE";
"B \NAC \NWC"3;
"S \NAC"
BN"34"93;
%"TAP"
"6","(-1600,3400)","2","mstr_standard","I77";
;
CDS_LIB"mstr_standard"
BODY_TYPE"PLUMBING"
HDL_TAP"TRUE";
"B \NAC \NWC"3;
"S \NAC"
BN"32"97;
%"TAP"
"6","(-1600,3350)","2","mstr_standard","I78";
;
CDS_LIB"mstr_standard"
BODY_TYPE"PLUMBING"
HDL_TAP"TRUE";
"B \NAC \NWC"3;
"S \NAC"
BN"33"96;
%"TAP"
"6","(-1600,3200)","2","mstr_standard","I79";
;
CDS_LIB"mstr_standard"
BODY_TYPE"PLUMBING"
HDL_TAP"TRUE";
"B \NAC \NWC"3;
"S \NAC"
BN"28"100;
%"TAP"
"6","(900,4800)","2","mstr_standard","I8";
;
CDS_LIB"mstr_standard"
BODY_TYPE"PLUMBING"
HDL_TAP"TRUE";
"B \NAC \NWC"2;
"S \NAC"
BN"14"167;
%"TAP"
"6","(-1600,3300)","2","mstr_standard","I80";
;
CDS_LIB"mstr_standard"
BODY_TYPE"PLUMBING"
HDL_TAP"TRUE";
"B \NAC \NWC"3;
"S \NAC"
BN"30"95;
%"TAP"
"6","(-1600,3250)","2","mstr_standard","I81";
;
CDS_LIB"mstr_standard"
BODY_TYPE"PLUMBING"
HDL_TAP"TRUE";
"B \NAC \NWC"3;
"S \NAC"
BN"31"94;
%"TAP"
"6","(-1600,3100)","2","mstr_standard","I82";
;
CDS_LIB"mstr_standard"
BODY_TYPE"PLUMBING"
HDL_TAP"TRUE";
"B \NAC \NWC"3;
"S \NAC"
BN"26"91;
%"TAP"
"6","(-1600,3150)","2","mstr_standard","I83";
;
CDS_LIB"mstr_standard"
BODY_TYPE"PLUMBING"
HDL_TAP"TRUE";
"B \NAC \NWC"3;
"S \NAC"
BN"29"99;
%"TAP"
"6","(-1600,3050)","2","mstr_standard","I84";
;
CDS_LIB"mstr_standard"
BODY_TYPE"PLUMBING"
HDL_TAP"TRUE";
"B \NAC \NWC"3;
"S \NAC"
BN"27"82;
%"TAP"
"6","(-1600,2950)","2","mstr_standard","I85";
;
CDS_LIB"mstr_standard"
BODY_TYPE"PLUMBING"
HDL_TAP"TRUE";
"B \NAC \NWC"3;
"S \NAC"
BN"25"88;
%"TAP"
"6","(-1600,3000)","2","mstr_standard","I86";
;
CDS_LIB"mstr_standard"
BODY_TYPE"PLUMBING"
HDL_TAP"TRUE";
"B \NAC \NWC"3;
"S \NAC"
BN"24"89;
%"TAP"
"6","(-1600,2850)","2","mstr_standard","I87";
;
CDS_LIB"mstr_standard"
BODY_TYPE"PLUMBING"
HDL_TAP"TRUE";
"B \NAC \NWC"3;
"S \NAC"
BN"23"86;
%"TAP"
"6","(-1600,2900)","2","mstr_standard","I88";
;
CDS_LIB"mstr_standard"
BODY_TYPE"PLUMBING"
HDL_TAP"TRUE";
"B \NAC \NWC"3;
"S \NAC"
BN"22"87;
%"TAP"
"6","(-1600,2800)","2","mstr_standard","I89";
;
CDS_LIB"mstr_standard"
BODY_TYPE"PLUMBING"
HDL_TAP"TRUE";
"B \NAC \NWC"3;
"S \NAC"
BN"20"90;
%"TAP"
"6","(900,4600)","2","mstr_standard","I9";
;
CDS_LIB"mstr_standard"
BODY_TYPE"PLUMBING"
HDL_TAP"TRUE";
"B \NAC \NWC"2;
"S \NAC"
BN"12"171;
%"TAP"
"6","(-1600,2750)","2","mstr_standard","I90";
;
CDS_LIB"mstr_standard"
BODY_TYPE"PLUMBING"
HDL_TAP"TRUE";
"B \NAC \NWC"3;
"S \NAC"
BN"21"85;
%"TAP"
"6","(-1600,2700)","2","mstr_standard","I91";
;
CDS_LIB"mstr_standard"
BODY_TYPE"PLUMBING"
HDL_TAP"TRUE";
"B \NAC \NWC"3;
"S \NAC"
BN"18"84;
%"TAP"
"6","(-1600,2650)","2","mstr_standard","I92";
;
CDS_LIB"mstr_standard"
BODY_TYPE"PLUMBING"
HDL_TAP"TRUE";
"B \NAC \NWC"3;
"S \NAC"
BN"19"83;
%"TAP"
"6","(-1600,2550)","2","mstr_standard","I93";
;
CDS_LIB"mstr_standard"
BODY_TYPE"PLUMBING"
HDL_TAP"TRUE";
"B \NAC \NWC"3;
"S \NAC"
BN"17"79;
%"TAP"
"6","(-1600,2600)","2","mstr_standard","I94";
;
CDS_LIB"mstr_standard"
BODY_TYPE"PLUMBING"
HDL_TAP"TRUE";
"B \NAC \NWC"3;
"S \NAC"
BN"16"81;
%"TAP"
"6","(-1600,2500)","2","mstr_standard","I95";
;
CDS_LIB"mstr_standard"
BODY_TYPE"PLUMBING"
HDL_TAP"TRUE";
"B \NAC \NWC"3;
"S \NAC"
BN"14"73;
%"TAP"
"6","(-1600,2450)","2","mstr_standard","I96";
;
CDS_LIB"mstr_standard"
BODY_TYPE"PLUMBING"
HDL_TAP"TRUE";
"B \NAC \NWC"3;
"S \NAC"
BN"15"78;
%"TAP"
"6","(-1600,2350)","2","mstr_standard","I97";
;
CDS_LIB"mstr_standard"
BODY_TYPE"PLUMBING"
HDL_TAP"TRUE";
"B \NAC \NWC"3;
"S \NAC"
BN"13"77;
%"TAP"
"6","(-1600,2400)","2","mstr_standard","I98";
;
CDS_LIB"mstr_standard"
BODY_TYPE"PLUMBING"
HDL_TAP"TRUE";
"B \NAC \NWC"3;
"S \NAC"
BN"12"80;
%"TAP"
"6","(-1600,2300)","2","mstr_standard","I99";
;
CDS_LIB"mstr_standard"
BODY_TYPE"PLUMBING"
HDL_TAP"TRUE";
"B \NAC \NWC"3;
"S \NAC"
BN"10"76;
END.
